# T6G (Grand Teton) — schematic netlist excerpt (pin names and nets, part order shuffled) for the footprints in the layout excerpt that follows; sources: Cadence DE-HDL packaged netlist, KiCad conversion of 04192023_DAF0TMB3IC0_F0TG_MB_C_brd_V02_OCP.brd

PC252  Q_CAP  1UF 16V 10% X6S  pkg C0402  page 210 : A = PVDDCR_CPU0_P1_VCC ; B = GND
C2335  Q_CAP  22UF 4V 20% X6S  pkg C0402  page 73 : A = PVDDCR_CPU0_P1 ; B = GND

(kicad_pcb
	(version 20260206)
	(generator "pcbnew")
	(generator_version "10.0")
	(general
		(thickness 1.6)
		(legacy_teardrops no)
	)
	(paper "A4")
	(title_block
		(title "04192023_DAF0TMB3IC0_F0TG_MB_C_brd_V02_OCP.brd")
		(comment 1 "Grand Teton / footprints 8162-8163 of 8354")
	)
	(layers
		(0 "F.Cu" signal "TOP")
		(4 "In1.Cu" signal "GND")
		(6 "In2.Cu" signal "IN1")
		(8 "In3.Cu" signal "GND1")
		(10 "In4.Cu" signal "IN2")
		(12 "In5.Cu" signal "GND2")
		(14 "In6.Cu" signal "IN3")
		(16 "In7.Cu" signal "GND3")
		(18 "In8.Cu" signal "VCC")
		(20 "In9.Cu" signal "VCC1")
		(22 "In10.Cu" signal "GND4")
		(24 "In11.Cu" signal "IN4")
		(26 "In12.Cu" signal "GND5")
		(28 "In13.Cu" signal "IN5")
		(30 "In14.Cu" signal "GND6")
		(32 "In15.Cu" signal "IN6")
		(34 "In16.Cu" signal "GND7")
		(2 "B.Cu" signal "BOTTOM")
		(9 "F.Adhes" user "F.Adhesive")
		(11 "B.Adhes" user "B.Adhesive")
		(13 "F.Paste" user "Package Geometry/Pastemask Top")
		(15 "B.Paste" user "Package Geometry/Pastemask Bottom")
		(5 "F.SilkS" user "Ref Des/Silkscreen Top")
		(7 "B.SilkS" user "Ref Des/Silkscreen Bottom")
		(1 "F.Mask" user "Board Geometry/Soldermask Top")
		(3 "B.Mask" user "Board Geometry/Soldermask Bottom")
		(17 "Dwgs.User" user "User.Drawings")
		(19 "Cmts.User" user "User.Comments")
		(21 "Eco1.User" user "User.Eco1")
		(23 "Eco2.User" user "User.Eco2")
		(25 "Edge.Cuts" user "Board Geometry/Outline")
		(27 "Margin" user)
		(31 "F.CrtYd" user "Package Geometry/Place Bound Top")
		(29 "B.CrtYd" user "Package Geometry/Place Bound Bottom")
		(35 "F.Fab" user "Ref Des/Assembly Top")
		(33 "B.Fab" user "Ref Des/Assembly Bottom")
	)
	(footprint ""
		(layer "B.Cu")
		(at 104.716834 -250.892564 180)
		(property "Reference" "C2335"
			(at 0 0 0)
			(layer "B.SilkS")
			(hide yes)
			(effects
				(font
					(size 1.27 1.27)
				)
				(justify mirror)
			)
		)
		(property "Value" ""
			(at 0 0 0)
			(layer "B.Fab")
			(effects
				(font
					(size 1.27 1.27)
				)
				(justify mirror)
			)
		)
		(duplicate_pad_numbers_are_jumpers no)
		(fp_line
			(start 0.7874 0.4064)
			(end 0.7874 -0.4064)
			(stroke
				(width 0.1524)
				(type default)
			)
			(layer "B.SilkS")
		)
		(fp_line
			(start 0.7874 -0.4064)
			(end -0.7874 -0.4064)
			(stroke
				(width 0.1524)
				(type default)
			)
			(layer "B.SilkS")
		)
		(fp_line
			(start -0.7874 0.4064)
			(end 0.7874 0.4064)
			(stroke
				(width 0.1524)
				(type default)
			)
			(layer "B.SilkS")
		)
		(fp_line
			(start -0.7874 -0.4064)
			(end -0.7874 0.4064)
			(stroke
				(width 0.1524)
				(type default)
			)
			(layer "B.SilkS")
		)
		(fp_line
			(start 0.67945 0.3048)
			(end 0.67945 -0.305054)
			(stroke
				(width 0.1)
				(type default)
			)
			(layer "B.Fab")
		)
		(fp_line
			(start 0.67945 -0.305054)
			(end 0.12065 -0.305054)
			(stroke
				(width 0.1)
				(type default)
			)
			(layer "B.Fab")
		)
		(fp_line
			(start 0.12065 0.3048)
			(end 0.67945 0.3048)
			(stroke
				(width 0.1)
				(type default)
			)
			(layer "B.Fab")
		)
		(fp_line
			(start 0.12065 0.2794)
			(end 0.12065 0.3048)
			(stroke
				(width 0.1)
				(type default)
			)
			(layer "B.Fab")
		)
		(fp_line
			(start 0.12065 -0.2794)
			(end -0.12065 -0.2794)
			(stroke
				(width 0.1)
				(type default)
			)
			(layer "B.Fab")
		)
		(fp_line
			(start 0.12065 -0.305054)
			(end 0.12065 -0.2794)
			(stroke
				(width 0.1)
				(type default)
			)
			(layer "B.Fab")
		)
		(fp_line
			(start -0.120396 0.3048)
			(end -0.120396 0.2794)
			(stroke
				(width 0.1)
				(type default)
			)
			(layer "B.Fab")
		)
		(fp_line
			(start -0.120396 0.2794)
			(end 0.12065 0.2794)
			(stroke
				(width 0.1)
				(type default)
			)
			(layer "B.Fab")
		)
		(fp_line
			(start -0.12065 -0.2794)
			(end -0.12065 -0.3048)
			(stroke
				(width 0.1)
				(type default)
			)
			(layer "B.Fab")
		)
		(fp_line
			(start -0.12065 -0.3048)
			(end -0.67945 -0.3048)
			(stroke
				(width 0.1)
				(type default)
			)
			(layer "B.Fab")
		)
		(fp_line
			(start -0.67945 0.3048)
			(end -0.120396 0.3048)
			(stroke
				(width 0.1)
				(type default)
			)
			(layer "B.Fab")
		)
		(fp_line
			(start -0.67945 -0.3048)
			(end -0.67945 0.3048)
			(stroke
				(width 0.1)
				(type default)
			)
			(layer "B.Fab")
		)
		(pad "1" smd circle
			(at 0.40005 0)
			(size 0 0)
			(layers "B.Cu" "B.Mask" "B.Paste")
			(net "PVDDCR_CPU0_P1")
		)
		(pad "2" smd circle
			(at -0.40005 0)
			(size 0 0)
			(layers "B.Cu" "B.Mask" "B.Paste")
			(net "GND")
		)
	)
	(footprint ""
		(layer "B.Cu")
		(at 101.512878 -139.93241 90)
		(property "Reference" "PC252"
			(at 0 0 90)
			(layer "B.SilkS")
			(hide yes)
			(effects
				(font
					(size 1.27 1.27)
				)
				(justify mirror)
			)
		)
		(property "Value" ""
			(at 0 0 90)
			(layer "B.Fab")
			(effects
				(font
					(size 1.27 1.27)
				)
				(justify mirror)
			)
		)
		(duplicate_pad_numbers_are_jumpers no)
		(fp_line
			(start 0.7874 -0.4064)
			(end -0.7874 -0.4064)
			(stroke
				(width 0.1524)
				(type default)
			)
			(layer "B.SilkS")
		)
		(fp_line
			(start -0.7874 -0.4064)
			(end -0.7874 0.4064)
			(stroke
				(width 0.1524)
				(type default)
			)
			(layer "B.SilkS")
		)
		(fp_line
			(start 0.7874 0.4064)
			(end 0.7874 -0.4064)
			(stroke
				(width 0.1524)
				(type default)
			)
			(layer "B.SilkS")
		)
		(fp_line
			(start -0.7874 0.4064)
			(end 0.7874 0.4064)
			(stroke
				(width 0.1524)
				(type default)
			)
			(layer "B.SilkS")
		)
		(fp_line
			(start 0.67945 -0.305054)
			(end 0.12065 -0.305054)
			(stroke
				(width 0.1)
				(type default)
			)
			(layer "B.Fab")
		)
		(fp_line
			(start 0.12065 -0.305054)
			(end 0.12065 -0.2794)
			(stroke
				(width 0.1)
				(type default)
			)
			(layer "B.Fab")
		)
		(fp_line
			(start -0.12065 -0.3048)
			(end -0.67945 -0.3048)
			(stroke
				(width 0.1)
				(type default)
			)
			(layer "B.Fab")
		)
		(fp_line
			(start -0.67945 -0.3048)
			(end -0.67945 0.3048)
			(stroke
				(width 0.1)
				(type default)
			)
			(layer "B.Fab")
		)
		(fp_line
			(start 0.12065 -0.2794)
			(end -0.12065 -0.2794)
			(stroke
				(width 0.1)
				(type default)
			)
			(layer "B.Fab")
		)
		(fp_line
			(start -0.12065 -0.2794)
			(end -0.12065 -0.3048)
			(stroke
				(width 0.1)
				(type default)
			)
			(layer "B.Fab")
		)
		(fp_line
			(start 0.12065 0.2794)
			(end 0.12065 0.3048)
			(stroke
				(width 0.1)
				(type default)
			)
			(layer "B.Fab")
		)
		(fp_line
			(start -0.120396 0.2794)
			(end 0.12065 0.2794)
			(stroke
				(width 0.1)
				(type default)
			)
			(layer "B.Fab")
		)
		(fp_line
			(start 0.67945 0.3048)
			(end 0.67945 -0.305054)
			(stroke
				(width 0.1)
				(type default)
			)
			(layer "B.Fab")
		)
		(fp_line
			(start 0.12065 0.3048)
			(end 0.67945 0.3048)
			(stroke
				(width 0.1)
				(type default)
			)
			(layer "B.Fab")
		)
		(fp_line
			(start -0.120396 0.3048)
			(end -0.120396 0.2794)
			(stroke
				(width 0.1)
				(type default)
			)
			(layer "B.Fab")
		)
		(fp_line
			(start -0.67945 0.3048)
			(end -0.120396 0.3048)
			(stroke
				(width 0.1)
				(type default)
			)
			(layer "B.Fab")
		)
		(pad "1" smd circle
			(at 0.40005 0 270)
			(size 0 0)
			(layers "B.Cu" "B.Mask" "B.Paste")
			(net "PVDDCR_CPU0_P1_VCC")
		)
		(pad "2" smd circle
			(at -0.40005 0 270)
			(size 0 0)
			(layers "B.Cu" "B.Mask" "B.Paste")
			(net "GND")
		)
	)
)
